(kicad_pcb
	(version 20260206)
	(generator "pcbnew")
	(generator_version "10.0")
	(general
		(thickness 1.6)
		(legacy_teardrops no)
	)
	(paper "A4")
	(title_block
		(title "04192023_DAF0TMB3IC0_F0TG_MB_C_brd_V02_OCP.brd")
		(comment 1 "Grand Teton / footprint 1120 of 8354 (J15), pads 1-113 of 291")
	)
	(layers
		(0 "F.Cu" signal "TOP")
		(4 "In1.Cu" signal "GND")
		(6 "In2.Cu" signal "IN1")
		(8 "In3.Cu" signal "GND1")
		(10 "In4.Cu" signal "IN2")
		(12 "In5.Cu" signal "GND2")
		(14 "In6.Cu" signal "IN3")
		(16 "In7.Cu" signal "GND3")
		(18 "In8.Cu" signal "VCC")
		(20 "In9.Cu" signal "VCC1")
		(22 "In10.Cu" signal "GND4")
		(24 "In11.Cu" signal "IN4")
		(26 "In12.Cu" signal "GND5")
		(28 "In13.Cu" signal "IN5")
		(30 "In14.Cu" signal "GND6")
		(32 "In15.Cu" signal "IN6")
		(34 "In16.Cu" signal "GND7")
		(2 "B.Cu" signal "BOTTOM")
		(9 "F.Adhes" user "F.Adhesive")
		(11 "B.Adhes" user "B.Adhesive")
		(13 "F.Paste" user "Package Geometry/Pastemask Top")
		(15 "B.Paste" user "Package Geometry/Pastemask Bottom")
		(5 "F.SilkS" user "Ref Des/Silkscreen Top")
		(7 "B.SilkS" user "Ref Des/Silkscreen Bottom")
		(1 "F.Mask" user "Board Geometry/Soldermask Top")
		(3 "B.Mask" user "Board Geometry/Soldermask Bottom")
		(17 "Dwgs.User" user "User.Drawings")
		(19 "Cmts.User" user "User.Comments")
		(21 "Eco1.User" user "User.Eco1")
		(23 "Eco2.User" user "User.Eco2")
		(25 "Edge.Cuts" user "Board Geometry/Outline")
		(27 "Margin" user)
		(31 "F.CrtYd" user "Package Geometry/Place Bound Top")
		(29 "B.CrtYd" user "Package Geometry/Place Bound Bottom")
		(35 "F.Fab" user "Ref Des/Assembly Top")
		(33 "B.Fab" user "Ref Des/Assembly Bottom")
	)
	(footprint ""
		(layer "F.Cu")
		(at 297.774106 -255.560068 180)
		(property "Reference" "J15"
			(at -2.2098 -81.984088 0)
			(unlocked yes)
			(layer "F.SilkS")
			(effects
				(font
					(size 0.7874 0.5842)
					(thickness 0.1524)
				)
			)
		)
		(property "Value" ""
			(at 0 0 180)
			(layer "F.Fab")
			(effects
				(font
					(size 1.27 1.27)
				)
			)
		)
		(duplicate_pad_numbers_are_jumpers no)
		(pad "1" smd rect
			(at -2.050034 -63.324994 90)
			(size 0.519938 1.4986)
			(layers "F.Cu" "F.Mask" "F.Paste")
			(net "P12V_MEM_CPU0")
		)
		(pad "2" smd rect
			(at -2.050034 -62.47511 90)
			(size 0.519938 1.4986)
			(layers "F.Cu" "F.Mask" "F.Paste")
			(net "Net_2263")
		)
		(pad "3" smd rect
			(at -2.050034 -61.624972 90)
			(size 0.519938 1.4986)
			(layers "F.Cu" "F.Mask" "F.Paste")
			(net "P3V3_AUX")
		)
		(pad "4" smd rect
			(at -2.050034 -60.775088 90)
			(size 0.519938 1.4986)
			(layers "F.Cu" "F.Mask" "F.Paste")
			(net "I3C_SPD_DDRB_CPU0_SCL")
		)
		(pad "5" smd rect
			(at -2.050034 -59.92495 90)
			(size 0.519938 1.4986)
			(layers "F.Cu" "F.Mask" "F.Paste")
			(net "I3C_SPD_DDRB_CPU0_SDA")
		)
		(pad "6" smd rect
			(at -2.050034 -59.075066 90)
			(size 0.519938 1.4986)
			(layers "F.Cu" "F.Mask" "F.Paste")
			(net "GND")
		)
		(pad "7" smd rect
			(at -2.050034 -58.224928 90)
			(size 0.519938 1.4986)
			(layers "F.Cu" "F.Mask" "F.Paste")
			(net "M_B_CPU0_SA_DQ<0>")
		)
		(pad "8" smd rect
			(at -2.050034 -57.375044 90)
			(size 0.519938 1.4986)
			(layers "F.Cu" "F.Mask" "F.Paste")
			(net "GND")
		)
		(pad "9" smd rect
			(at -2.050034 -56.524906 90)
			(size 0.519938 1.4986)
			(layers "F.Cu" "F.Mask" "F.Paste")
			(net "M_B_CPU0_SA_DQ<1>")
		)
		(pad "10" smd rect
			(at -2.050034 -55.675022 90)
			(size 0.519938 1.4986)
			(layers "F.Cu" "F.Mask" "F.Paste")
			(net "GND")
		)
		(pad "11" smd rect
			(at -2.050034 -54.824884 90)
			(size 0.519938 1.4986)
			(layers "F.Cu" "F.Mask" "F.Paste")
			(net "M_B_CPU0_SA_DQS_DP<0>")
		)
		(pad "12" smd rect
			(at -2.050034 -53.975 90)
			(size 0.519938 1.4986)
			(layers "F.Cu" "F.Mask" "F.Paste")
			(net "M_B_CPU0_SA_DQS_DN<0>")
		)
		(pad "13" smd rect
			(at -2.050034 -53.125116 90)
			(size 0.519938 1.4986)
			(layers "F.Cu" "F.Mask" "F.Paste")
			(net "GND")
		)
		(pad "14" smd rect
			(at -2.050034 -52.274978 90)
			(size 0.519938 1.4986)
			(layers "F.Cu" "F.Mask" "F.Paste")
			(net "M_B_CPU0_SA_DQ<4>")
		)
		(pad "15" smd rect
			(at -2.050034 -51.425094 90)
			(size 0.519938 1.4986)
			(layers "F.Cu" "F.Mask" "F.Paste")
			(net "GND")
		)
		(pad "16" smd rect
			(at -2.050034 -50.574956 90)
			(size 0.519938 1.4986)
			(layers "F.Cu" "F.Mask" "F.Paste")
			(net "M_B_CPU0_SA_DQ<5>")
		)
		(pad "17" smd rect
			(at -2.050034 -49.725072 90)
			(size 0.519938 1.4986)
			(layers "F.Cu" "F.Mask" "F.Paste")
			(net "GND")
		)
		(pad "18" smd rect
			(at -2.050034 -48.874934 90)
			(size 0.519938 1.4986)
			(layers "F.Cu" "F.Mask" "F.Paste")
			(net "M_B_CPU0_SA_DQ<8>")
		)
		(pad "19" smd rect
			(at -2.050034 -48.02505 90)
			(size 0.519938 1.4986)
			(layers "F.Cu" "F.Mask" "F.Paste")
			(net "GND")
		)
		(pad "20" smd rect
			(at -2.050034 -47.174912 90)
			(size 0.519938 1.4986)
			(layers "F.Cu" "F.Mask" "F.Paste")
			(net "M_B_CPU0_SA_DQ<9>")
		)
		(pad "21" smd rect
			(at -2.050034 -46.325028 90)
			(size 0.519938 1.4986)
			(layers "F.Cu" "F.Mask" "F.Paste")
			(net "GND")
		)
		(pad "22" smd rect
			(at -2.050034 -45.47489 90)
			(size 0.519938 1.4986)
			(layers "F.Cu" "F.Mask" "F.Paste")
			(net "M_B_CPU0_SA_DQS_DP<1>")
		)
		(pad "23" smd rect
			(at -2.050034 -44.625006 90)
			(size 0.519938 1.4986)
			(layers "F.Cu" "F.Mask" "F.Paste")
			(net "M_B_CPU0_SA_DQS_DN<1>")
		)
		(pad "24" smd rect
			(at -2.050034 -43.775122 90)
			(size 0.519938 1.4986)
			(layers "F.Cu" "F.Mask" "F.Paste")
			(net "GND")
		)
		(pad "25" smd rect
			(at -2.050034 -42.924984 90)
			(size 0.519938 1.4986)
			(layers "F.Cu" "F.Mask" "F.Paste")
			(net "M_B_CPU0_SA_DQ<12>")
		)
		(pad "26" smd rect
			(at -2.050034 -42.0751 90)
			(size 0.519938 1.4986)
			(layers "F.Cu" "F.Mask" "F.Paste")
			(net "GND")
		)
		(pad "27" smd rect
			(at -2.050034 -41.224962 90)
			(size 0.519938 1.4986)
			(layers "F.Cu" "F.Mask" "F.Paste")
			(net "M_B_CPU0_SA_DQ<13>")
		)
		(pad "28" smd rect
			(at -2.050034 -40.375078 90)
			(size 0.519938 1.4986)
			(layers "F.Cu" "F.Mask" "F.Paste")
			(net "GND")
		)
		(pad "29" smd rect
			(at -2.050034 -39.52494 90)
			(size 0.519938 1.4986)
			(layers "F.Cu" "F.Mask" "F.Paste")
			(net "M_B_CPU0_SA_DQ<16>")
		)
		(pad "30" smd rect
			(at -2.050034 -38.675056 90)
			(size 0.519938 1.4986)
			(layers "F.Cu" "F.Mask" "F.Paste")
			(net "GND")
		)
		(pad "31" smd rect
			(at -2.050034 -37.824918 90)
			(size 0.519938 1.4986)
			(layers "F.Cu" "F.Mask" "F.Paste")
			(net "M_B_CPU0_SA_DQ<17>")
		)
		(pad "32" smd rect
			(at -2.050034 -36.975034 90)
			(size 0.519938 1.4986)
			(layers "F.Cu" "F.Mask" "F.Paste")
			(net "GND")
		)
		(pad "33" smd rect
			(at -2.050034 -36.124896 90)
			(size 0.519938 1.4986)
			(layers "F.Cu" "F.Mask" "F.Paste")
			(net "M_B_CPU0_SA_DQS_DP<2>")
		)
		(pad "34" smd rect
			(at -2.050034 -35.275012 90)
			(size 0.519938 1.4986)
			(layers "F.Cu" "F.Mask" "F.Paste")
			(net "M_B_CPU0_SA_DQS_DN<2>")
		)
		(pad "35" smd rect
			(at -2.050034 -34.425128 90)
			(size 0.519938 1.4986)
			(layers "F.Cu" "F.Mask" "F.Paste")
			(net "GND")
		)
		(pad "36" smd rect
			(at -2.050034 -33.57499 90)
			(size 0.519938 1.4986)
			(layers "F.Cu" "F.Mask" "F.Paste")
			(net "M_B_CPU0_SA_DQ<20>")
		)
		(pad "37" smd rect
			(at -2.050034 -32.725106 90)
			(size 0.519938 1.4986)
			(layers "F.Cu" "F.Mask" "F.Paste")
			(net "GND")
		)
		(pad "38" smd rect
			(at -2.050034 -31.874968 90)
			(size 0.519938 1.4986)
			(layers "F.Cu" "F.Mask" "F.Paste")
			(net "M_B_CPU0_SA_DQ<21>")
		)
		(pad "39" smd rect
			(at -2.050034 -31.025084 90)
			(size 0.519938 1.4986)
			(layers "F.Cu" "F.Mask" "F.Paste")
			(net "GND")
		)
		(pad "40" smd rect
			(at -2.050034 -30.174946 90)
			(size 0.519938 1.4986)
			(layers "F.Cu" "F.Mask" "F.Paste")
			(net "M_B_CPU0_SA_DQ<24>")
		)
		(pad "41" smd rect
			(at -2.050034 -29.325062 90)
			(size 0.519938 1.4986)
			(layers "F.Cu" "F.Mask" "F.Paste")
			(net "GND")
		)
		(pad "42" smd rect
			(at -2.050034 -28.474924 90)
			(size 0.519938 1.4986)
			(layers "F.Cu" "F.Mask" "F.Paste")
			(net "M_B_CPU0_SA_DQ<25>")
		)
		(pad "43" smd rect
			(at -2.050034 -27.62504 90)
			(size 0.519938 1.4986)
			(layers "F.Cu" "F.Mask" "F.Paste")
			(net "GND")
		)
		(pad "44" smd rect
			(at -2.050034 -26.774902 90)
			(size 0.519938 1.4986)
			(layers "F.Cu" "F.Mask" "F.Paste")
			(net "M_B_CPU0_SA_DQS_DP<3>")
		)
		(pad "45" smd rect
			(at -2.050034 -25.925018 90)
			(size 0.519938 1.4986)
			(layers "F.Cu" "F.Mask" "F.Paste")
			(net "M_B_CPU0_SA_DQS_DN<3>")
		)
		(pad "46" smd rect
			(at -2.050034 -25.07488 90)
			(size 0.519938 1.4986)
			(layers "F.Cu" "F.Mask" "F.Paste")
			(net "GND")
		)
		(pad "47" smd rect
			(at -2.050034 -24.224996 90)
			(size 0.519938 1.4986)
			(layers "F.Cu" "F.Mask" "F.Paste")
			(net "M_B_CPU0_SA_DQ<28>")
		)
		(pad "48" smd rect
			(at -2.050034 -23.375112 90)
			(size 0.519938 1.4986)
			(layers "F.Cu" "F.Mask" "F.Paste")
			(net "GND")
		)
		(pad "49" smd rect
			(at -2.050034 -22.524974 90)
			(size 0.519938 1.4986)
			(layers "F.Cu" "F.Mask" "F.Paste")
			(net "M_B_CPU0_SA_DQ<29>")
		)
		(pad "50" smd rect
			(at -2.050034 -21.67509 90)
			(size 0.519938 1.4986)
			(layers "F.Cu" "F.Mask" "F.Paste")
			(net "GND")
		)
		(pad "51" smd rect
			(at -2.050034 -20.824952 90)
			(size 0.519938 1.4986)
			(layers "F.Cu" "F.Mask" "F.Paste")
			(net "M_B_CPU0_SA_CB<0>")
		)
		(pad "52" smd rect
			(at -2.050034 -19.975068 90)
			(size 0.519938 1.4986)
			(layers "F.Cu" "F.Mask" "F.Paste")
			(net "GND")
		)
		(pad "53" smd rect
			(at -2.050034 -19.12493 90)
			(size 0.519938 1.4986)
			(layers "F.Cu" "F.Mask" "F.Paste")
			(net "M_B_CPU0_SA_CB<1>")
		)
		(pad "54" smd rect
			(at -2.050034 -18.275046 90)
			(size 0.519938 1.4986)
			(layers "F.Cu" "F.Mask" "F.Paste")
			(net "GND")
		)
		(pad "55" smd rect
			(at -2.050034 -17.424908 90)
			(size 0.519938 1.4986)
			(layers "F.Cu" "F.Mask" "F.Paste")
			(net "M_B_CPU0_SA_DQS_DP<4>")
		)
		(pad "56" smd rect
			(at -2.050034 -16.575024 90)
			(size 0.519938 1.4986)
			(layers "F.Cu" "F.Mask" "F.Paste")
			(net "M_B_CPU0_SA_DQS_DN<4>")
		)
		(pad "57" smd rect
			(at -2.050034 -15.724886 90)
			(size 0.519938 1.4986)
			(layers "F.Cu" "F.Mask" "F.Paste")
			(net "GND")
		)
		(pad "58" smd rect
			(at -2.050034 -14.875002 90)
			(size 0.519938 1.4986)
			(layers "F.Cu" "F.Mask" "F.Paste")
			(net "M_B_CPU0_SA_CB<4>")
		)
		(pad "59" smd rect
			(at -2.050034 -14.025118 90)
			(size 0.519938 1.4986)
			(layers "F.Cu" "F.Mask" "F.Paste")
			(net "GND")
		)
		(pad "60" smd rect
			(at -2.050034 -13.17498 90)
			(size 0.519938 1.4986)
			(layers "F.Cu" "F.Mask" "F.Paste")
			(net "M_B_CPU0_SA_CB<5>")
		)
		(pad "61" smd rect
			(at -2.050034 -12.325096 90)
			(size 0.519938 1.4986)
			(layers "F.Cu" "F.Mask" "F.Paste")
			(net "GND")
		)
		(pad "62" smd rect
			(at -2.050034 -11.474958 90)
			(size 0.519938 1.4986)
			(layers "F.Cu" "F.Mask" "F.Paste")
			(net "M_B_CPU0_ALERT_N")
		)
		(pad "63" smd rect
			(at -2.050034 -10.625074 90)
			(size 0.519938 1.4986)
			(layers "F.Cu" "F.Mask" "F.Paste")
			(net "GND")
		)
		(pad "64" smd rect
			(at -2.050034 -9.774936 90)
			(size 0.519938 1.4986)
			(layers "F.Cu" "F.Mask" "F.Paste")
			(net "M_B_CPU0_SA_CS_N<0>")
		)
		(pad "65" smd rect
			(at -2.050034 -8.925052 90)
			(size 0.519938 1.4986)
			(layers "F.Cu" "F.Mask" "F.Paste")
			(net "GND")
		)
		(pad "66" smd rect
			(at -2.050034 -8.074914 90)
			(size 0.519938 1.4986)
			(layers "F.Cu" "F.Mask" "F.Paste")
			(net "M_B_CPU0_SA_CA<0>")
		)
		(pad "67" smd rect
			(at -2.050034 -7.22503 90)
			(size 0.519938 1.4986)
			(layers "F.Cu" "F.Mask" "F.Paste")
			(net "GND")
		)
		(pad "68" smd rect
			(at -2.050034 -6.374892 90)
			(size 0.519938 1.4986)
			(layers "F.Cu" "F.Mask" "F.Paste")
			(net "M_B_CPU0_SA_CA<2>")
		)
		(pad "69" smd rect
			(at -2.050034 -5.525008 90)
			(size 0.519938 1.4986)
			(layers "F.Cu" "F.Mask" "F.Paste")
			(net "GND")
		)
		(pad "70" smd rect
			(at -2.050034 -4.675124 90)
			(size 0.519938 1.4986)
			(layers "F.Cu" "F.Mask" "F.Paste")
			(net "M_B_CPU0_SA_CA<4>")
		)
		(pad "71" smd rect
			(at -2.050034 -3.824986 90)
			(size 0.519938 1.4986)
			(layers "F.Cu" "F.Mask" "F.Paste")
			(net "GND")
		)
		(pad "72" smd rect
			(at -2.050034 -2.975102 90)
			(size 0.519938 1.4986)
			(layers "F.Cu" "F.Mask" "F.Paste")
			(net "M_B_CPU0_SA_CA<6>")
		)
		(pad "73" smd rect
			(at -2.050034 -2.124964 90)
			(size 0.519938 1.4986)
			(layers "F.Cu" "F.Mask" "F.Paste")
			(net "GND")
		)
		(pad "74" smd rect
			(at -2.050034 -1.27508 90)
			(size 0.519938 1.4986)
			(layers "F.Cu" "F.Mask" "F.Paste")
			(net "M_B_CPU0_SA_PAR")
		)
		(pad "75" smd rect
			(at -2.050034 -0.424942 90)
			(size 0.519938 1.4986)
			(layers "F.Cu" "F.Mask" "F.Paste")
			(net "GND")
		)
		(pad "76" smd rect
			(at -2.050034 5.525008 90)
			(size 0.519938 1.4986)
			(layers "F.Cu" "F.Mask" "F.Paste")
			(net "M_B_CPU0_SB_CA<0>")
		)
		(pad "77" smd rect
			(at -2.050034 6.374892 90)
			(size 0.519938 1.4986)
			(layers "F.Cu" "F.Mask" "F.Paste")
			(net "GND")
		)
		(pad "78" smd rect
			(at -2.050034 7.22503 90)
			(size 0.519938 1.4986)
			(layers "F.Cu" "F.Mask" "F.Paste")
			(net "M_B_CPU0_SB_CA<2>")
		)
		(pad "79" smd rect
			(at -2.050034 8.074914 90)
			(size 0.519938 1.4986)
			(layers "F.Cu" "F.Mask" "F.Paste")
			(net "GND")
		)
		(pad "80" smd rect
			(at -2.050034 8.925052 90)
			(size 0.519938 1.4986)
			(layers "F.Cu" "F.Mask" "F.Paste")
			(net "M_B_CPU0_SB_CA<4>")
		)
		(pad "81" smd rect
			(at -2.050034 9.774936 90)
			(size 0.519938 1.4986)
			(layers "F.Cu" "F.Mask" "F.Paste")
			(net "GND")
		)
		(pad "82" smd rect
			(at -2.050034 10.625074 90)
			(size 0.519938 1.4986)
			(layers "F.Cu" "F.Mask" "F.Paste")
			(net "M_B_CPU0_SB_CA<6>")
		)
		(pad "83" smd rect
			(at -2.050034 11.474958 90)
			(size 0.519938 1.4986)
			(layers "F.Cu" "F.Mask" "F.Paste")
			(net "GND")
		)
		(pad "84" smd rect
			(at -2.050034 12.325096 90)
			(size 0.519938 1.4986)
			(layers "F.Cu" "F.Mask" "F.Paste")
			(net "M_B_CPU0_SB_CS_N<0>")
		)
		(pad "85" smd rect
			(at -2.050034 13.17498 90)
			(size 0.519938 1.4986)
			(layers "F.Cu" "F.Mask" "F.Paste")
			(net "GND")
		)
		(pad "86" smd rect
			(at -2.050034 14.025118 90)
			(size 0.519938 1.4986)
			(layers "F.Cu" "F.Mask" "F.Paste")
			(net "M_B_CPU0_SA_RSP<0>")
		)
		(pad "87" smd rect
			(at -2.050034 14.875002 90)
			(size 0.519938 1.4986)
			(layers "F.Cu" "F.Mask" "F.Paste")
			(net "M_B_CPU0_SB_RSP<0>")
		)
		(pad "88" smd rect
			(at -2.050034 15.724886 90)
			(size 0.519938 1.4986)
			(layers "F.Cu" "F.Mask" "F.Paste")
			(net "GND")
		)
		(pad "89" smd rect
			(at -2.050034 16.575024 90)
			(size 0.519938 1.4986)
			(layers "F.Cu" "F.Mask" "F.Paste")
			(net "M_B_CPU0_SB_CB<4>")
		)
		(pad "90" smd rect
			(at -2.050034 17.424908 90)
			(size 0.519938 1.4986)
			(layers "F.Cu" "F.Mask" "F.Paste")
			(net "GND")
		)
		(pad "91" smd rect
			(at -2.050034 18.275046 90)
			(size 0.519938 1.4986)
			(layers "F.Cu" "F.Mask" "F.Paste")
			(net "M_B_CPU0_SB_CB<5>")
		)
		(pad "92" smd rect
			(at -2.050034 19.12493 90)
			(size 0.519938 1.4986)
			(layers "F.Cu" "F.Mask" "F.Paste")
			(net "GND")
		)
		(pad "93" smd rect
			(at -2.050034 19.975068 90)
			(size 0.519938 1.4986)
			(layers "F.Cu" "F.Mask" "F.Paste")
			(net "M_B_CPU0_SB_DQS_DP<9>")
		)
		(pad "94" smd rect
			(at -2.050034 20.824952 90)
			(size 0.519938 1.4986)
			(layers "F.Cu" "F.Mask" "F.Paste")
			(net "M_B_CPU0_SB_DQS_DN<9>")
		)
		(pad "95" smd rect
			(at -2.050034 21.67509 90)
			(size 0.519938 1.4986)
			(layers "F.Cu" "F.Mask" "F.Paste")
			(net "GND")
		)
		(pad "96" smd rect
			(at -2.050034 22.524974 90)
			(size 0.519938 1.4986)
			(layers "F.Cu" "F.Mask" "F.Paste")
			(net "M_B_CPU0_SB_CB<0>")
		)
		(pad "97" smd rect
			(at -2.050034 23.375112 90)
			(size 0.519938 1.4986)
			(layers "F.Cu" "F.Mask" "F.Paste")
			(net "GND")
		)
		(pad "98" smd rect
			(at -2.050034 24.224996 90)
			(size 0.519938 1.4986)
			(layers "F.Cu" "F.Mask" "F.Paste")
			(net "M_B_CPU0_SB_CB<1>")
		)
		(pad "99" smd rect
			(at -2.050034 25.07488 90)
			(size 0.519938 1.4986)
			(layers "F.Cu" "F.Mask" "F.Paste")
			(net "GND")
		)
		(pad "100" smd rect
			(at -2.050034 25.925018 90)
			(size 0.519938 1.4986)
			(layers "F.Cu" "F.Mask" "F.Paste")
			(net "M_B_CPU0_SB_DQ<0>")
		)
		(pad "101" smd rect
			(at -2.050034 26.774902 90)
			(size 0.519938 1.4986)
			(layers "F.Cu" "F.Mask" "F.Paste")
			(net "GND")
		)
		(pad "102" smd rect
			(at -2.050034 27.62504 90)
			(size 0.519938 1.4986)
			(layers "F.Cu" "F.Mask" "F.Paste")
			(net "M_B_CPU0_SB_DQ<1>")
		)
		(pad "103" smd rect
			(at -2.050034 28.474924 90)
			(size 0.519938 1.4986)
			(layers "F.Cu" "F.Mask" "F.Paste")
			(net "GND")
		)
		(pad "104" smd rect
			(at -2.050034 29.325062 90)
			(size 0.519938 1.4986)
			(layers "F.Cu" "F.Mask" "F.Paste")
			(net "M_B_CPU0_SB_DQS_DP<0>")
		)
		(pad "105" smd rect
			(at -2.050034 30.174946 90)
			(size 0.519938 1.4986)
			(layers "F.Cu" "F.Mask" "F.Paste")
			(net "M_B_CPU0_SB_DQS_DN<0>")
		)
		(pad "106" smd rect
			(at -2.050034 31.025084 90)
			(size 0.519938 1.4986)
			(layers "F.Cu" "F.Mask" "F.Paste")
			(net "GND")
		)
		(pad "107" smd rect
			(at -2.050034 31.874968 90)
			(size 0.519938 1.4986)
			(layers "F.Cu" "F.Mask" "F.Paste")
			(net "M_B_CPU0_SB_DQ<4>")
		)
		(pad "108" smd rect
			(at -2.050034 32.725106 90)
			(size 0.519938 1.4986)
			(layers "F.Cu" "F.Mask" "F.Paste")
			(net "GND")
		)
		(pad "109" smd rect
			(at -2.050034 33.57499 90)
			(size 0.519938 1.4986)
			(layers "F.Cu" "F.Mask" "F.Paste")
			(net "M_B_CPU0_SB_DQ<5>")
		)
		(pad "110" smd rect
			(at -2.050034 34.425128 90)
			(size 0.519938 1.4986)
			(layers "F.Cu" "F.Mask" "F.Paste")
			(net "GND")
		)
		(pad "111" smd rect
			(at -2.050034 35.275012 90)
			(size 0.519938 1.4986)
			(layers "F.Cu" "F.Mask" "F.Paste")
			(net "M_B_CPU0_SB_DQ<8>")
		)
		(pad "112" smd rect
			(at -2.050034 36.124896 90)
			(size 0.519938 1.4986)
			(layers "F.Cu" "F.Mask" "F.Paste")
			(net "GND")
		)
		(pad "113" smd rect
			(at -2.050034 36.975034 90)
			(size 0.519938 1.4986)
			(layers "F.Cu" "F.Mask" "F.Paste")
			(net "M_B_CPU0_SB_DQ<9>")
		)
	)
)
